(kicad_pcb
	(version 20241229)
	(generator "pcbnew")
	(generator_version "9.0")
	(general
		(thickness 1.62)
		(legacy_teardrops no)
	)
	(paper "A3")
	(title_block
		(title "COM Express 7 Baseboard")
		(date "2025-02-04")
		(rev "1.1.2")
		(company "Antmicro Ltd")
		(comment 1 "www.antmicro.com")
		(comment 9 "footprint 486 of 802 (U45), pads 40-79 of 144")
	)
	(layers
		(0 "F.Cu" signal)
		(4 "In1.Cu" signal)
		(6 "In2.Cu" signal)
		(8 "In3.Cu" signal)
		(10 "In4.Cu" signal)
		(12 "In5.Cu" signal)
		(14 "In6.Cu" signal)
		(2 "B.Cu" signal)
		(9 "F.Adhes" user "F.Adhesive")
		(11 "B.Adhes" user "B.Adhesive")
		(13 "F.Paste" user)
		(15 "B.Paste" user)
		(5 "F.SilkS" user "F.Silkscreen")
		(7 "B.SilkS" user "B.Silkscreen")
		(1 "F.Mask" user)
		(3 "B.Mask" user)
		(17 "Dwgs.User" user "User.Drawings")
		(19 "Cmts.User" user "User.Comments")
		(21 "Eco1.User" user "User.Eco1")
		(23 "Eco2.User" user "User.Eco2")
		(25 "Edge.Cuts" user)
		(27 "Margin" user)
		(31 "F.CrtYd" user "F.Courtyard")
		(29 "B.CrtYd" user "B.Courtyard")
		(35 "F.Fab" user)
		(33 "B.Fab" user)
	)
	(footprint "antmicro-footprints:BGA-144_12x12_13.05x13.05mm_P1.0mm"
		(layer "F.Cu")
		(at 132.79 137.36 -90)
		(property "Reference" "U45"
			(at 7.9 4.85 180)
			(layer "F.SilkS")
			(effects
				(font
					(size 0.7 0.7)
					(thickness 0.15)
				)
				(justify right bottom)
			)
		)
		(property "Value" "TLK10232CTR"
			(at 0 7.525 90)
			(layer "F.Fab")
			(effects
				(font
					(size 0.7 0.7)
					(thickness 0.15)
				)
				(justify right bottom)
			)
		)
		(property "Datasheet" "https://www.ti.com/lit/ds/symlink/tlk10232.pdf?ts=1712150848075&ref_url=https%253A%252F%252Fwww.mouser.pl%252F"
			(at 0 0 270)
			(layer "F.Fab")
			(hide yes)
			(effects
				(font
					(size 1.27 1.27)
					(thickness 0.15)
				)
			)
		)
		(property "Author" "Antmicro"
			(at -4.57 270.15 0)
			(layer "F.Fab")
			(hide yes)
			(effects
				(font
					(size 1 1)
					(thickness 0.15)
				)
			)
		)
		(property "License" "Apache-2.0"
			(at -4.57 270.15 0)
			(layer "F.Fab")
			(hide yes)
			(effects
				(font
					(size 1 1)
					(thickness 0.15)
				)
			)
		)
		(property "MPN" "TLK10232CTR"
			(at -4.57 270.15 0)
			(layer "F.Fab")
			(hide yes)
			(effects
				(font
					(size 1 1)
					(thickness 0.15)
				)
			)
		)
		(property "Manufacturer" "Texas Instruments"
			(at -4.57 270.15 0)
			(layer "F.Fab")
			(hide yes)
			(effects
				(font
					(size 1 1)
					(thickness 0.15)
				)
			)
		)
		(sheetname "KR to SFI #2")
		(sheetfile "kr_sfi.kicad_sch")
		(attr smd)
		(pad "D4" smd circle
			(at -2.5 -2.5 270)
			(size 0.5 0.5)
			(layers "F.Cu" "F.Mask" "F.Paste")
			(net 749 "Net-(U45C-AMUXB)")
			(pinfunction "AMUXB")
			(pintype "passive")
			(solder_mask_margin 0.05)
			(teardrops
				(best_length_ratio 0.4)
				(max_length 1)
				(best_width_ratio 0.9)
				(max_width 2)
				(curved_edges yes)
				(filter_ratio 0.9)
				(enabled yes)
				(allow_two_segments yes)
				(prefer_zone_connections yes)
			)
		)
		(pad "D5" smd circle
			(at -1.5 -2.5 270)
			(size 0.5 0.5)
			(layers "F.Cu" "F.Mask" "F.Paste")
			(net 1 "GND")
			(pinfunction "GND")
			(pintype "passive")
			(solder_mask_margin 0.05)
			(teardrops
				(best_length_ratio 0.4)
				(max_length 1)
				(best_width_ratio 0.9)
				(max_width 2)
				(curved_edges yes)
				(filter_ratio 0.9)
				(enabled yes)
				(allow_two_segments yes)
				(prefer_zone_connections yes)
			)
		)
		(pad "D6" smd circle
			(at -0.5 -2.5 270)
			(size 0.5 0.5)
			(layers "F.Cu" "F.Mask" "F.Paste")
			(net 743 "/2xSFP+/KR to SFI #2/TDO")
			(pinfunction "TDO")
			(pintype "output")
			(solder_mask_margin 0.05)
			(teardrops
				(best_length_ratio 0.4)
				(max_length 1)
				(best_width_ratio 0.9)
				(max_width 2)
				(curved_edges yes)
				(filter_ratio 0.9)
				(enabled yes)
				(allow_two_segments yes)
				(prefer_zone_connections yes)
			)
		)
		(pad "D7" smd circle
			(at 0.5 -2.5 270)
			(size 0.5 0.5)
			(layers "F.Cu" "F.Mask" "F.Paste")
			(net 74 "+1V0")
			(pinfunction "VPP")
			(pintype "power_in")
			(solder_mask_margin 0.05)
			(teardrops
				(best_length_ratio 0.4)
				(max_length 1)
				(best_width_ratio 0.9)
				(max_width 2)
				(curved_edges yes)
				(filter_ratio 0.9)
				(enabled yes)
				(allow_two_segments yes)
				(prefer_zone_connections yes)
			)
		)
		(pad "D8" smd circle
			(at 1.5 -2.5 270)
			(size 0.5 0.5)
			(layers "F.Cu" "F.Mask" "F.Paste")
			(net 745 "/2xSFP+/KR to SFI #2/TCK")
			(pinfunction "TCK")
			(pintype "input")
			(solder_mask_margin 0.05)
			(teardrops
				(best_length_ratio 0.4)
				(max_length 1)
				(best_width_ratio 0.9)
				(max_width 2)
				(curved_edges yes)
				(filter_ratio 0.9)
				(enabled yes)
				(allow_two_segments yes)
				(prefer_zone_connections yes)
			)
		)
		(pad "D9" smd circle
			(at 2.5 -2.5 270)
			(size 0.5 0.5)
			(layers "F.Cu" "F.Mask" "F.Paste")
			(net 756 "Net-(U45A-LS_OK_{OUT_A})")
			(pinfunction "LS_OK_{OUT_A}")
			(pintype "output")
			(solder_mask_margin 0.05)
			(teardrops
				(best_length_ratio 0.4)
				(max_length 1)
				(best_width_ratio 0.9)
				(max_width 2)
				(curved_edges yes)
				(filter_ratio 0.9)
				(enabled yes)
				(allow_two_segments yes)
				(prefer_zone_connections yes)
			)
		)
		(pad "D10" smd circle
			(at 3.5 -2.5 270)
			(size 0.5 0.5)
			(layers "F.Cu" "F.Mask" "F.Paste")
			(net 1 "GND")
			(pinfunction "GND")
			(pintype "passive")
			(solder_mask_margin 0.05)
			(teardrops
				(best_length_ratio 0.4)
				(max_length 1)
				(best_width_ratio 0.9)
				(max_width 2)
				(curved_edges yes)
				(filter_ratio 0.9)
				(enabled yes)
				(allow_two_segments yes)
				(prefer_zone_connections yes)
			)
		)
		(pad "D11" smd circle
			(at 4.5 -2.5 270)
			(size 0.5 0.5)
			(layers "F.Cu" "F.Mask" "F.Paste")
			(net 1 "GND")
			(pinfunction "GND")
			(pintype "passive")
			(solder_mask_margin 0.05)
			(teardrops
				(best_length_ratio 0.4)
				(max_length 1)
				(best_width_ratio 0.9)
				(max_width 2)
				(curved_edges yes)
				(filter_ratio 0.9)
				(enabled yes)
				(allow_two_segments yes)
				(prefer_zone_connections yes)
			)
		)
		(pad "D12" smd circle
			(at 5.5 -2.5 270)
			(size 0.5 0.5)
			(layers "F.Cu" "F.Mask" "F.Paste")
			(net 687 "/2xSFP+/KR to SFI #2/KR_R.RX+")
			(pinfunction "HSTXA+")
			(pintype "output")
			(solder_mask_margin 0.05)
			(teardrops
				(best_length_ratio 0.4)
				(max_length 1)
				(best_width_ratio 0.9)
				(max_width 2)
				(curved_edges yes)
				(filter_ratio 0.9)
				(enabled yes)
				(allow_two_segments yes)
				(prefer_zone_connections yes)
			)
		)
		(pad "E1" smd circle
			(at -5.5 -1.5 270)
			(size 0.5 0.5)
			(layers "F.Cu" "F.Mask" "F.Paste")
			(net 845 "unconnected-(U45A-INA3--PadE1)")
			(pinfunction "INA3-")
			(pintype "input+no_connect")
			(solder_mask_margin 0.05)
			(teardrops
				(best_length_ratio 0.4)
				(max_length 1)
				(best_width_ratio 0.9)
				(max_width 2)
				(curved_edges yes)
				(filter_ratio 0.9)
				(enabled yes)
				(allow_two_segments yes)
				(prefer_zone_connections yes)
			)
		)
		(pad "E2" smd circle
			(at -4.5 -1.5 270)
			(size 0.5 0.5)
			(layers "F.Cu" "F.Mask" "F.Paste")
			(net 1 "GND")
			(pinfunction "GND")
			(pintype "passive")
			(solder_mask_margin 0.05)
			(teardrops
				(best_length_ratio 0.4)
				(max_length 1)
				(best_width_ratio 0.9)
				(max_width 2)
				(curved_edges yes)
				(filter_ratio 0.9)
				(enabled yes)
				(allow_two_segments yes)
				(prefer_zone_connections yes)
			)
		)
		(pad "E3" smd circle
			(at -3.5 -1.5 270)
			(size 0.5 0.5)
			(layers "F.Cu" "F.Mask" "F.Paste")
			(net 846 "unconnected-(U45A-OUTA3--PadE3)")
			(pinfunction "OUTA3-")
			(pintype "output+no_connect")
			(solder_mask_margin 0.05)
			(teardrops
				(best_length_ratio 0.4)
				(max_length 1)
				(best_width_ratio 0.9)
				(max_width 2)
				(curved_edges yes)
				(filter_ratio 0.9)
				(enabled yes)
				(allow_two_segments yes)
				(prefer_zone_connections yes)
			)
		)
		(pad "E4" smd circle
			(at -2.5 -1.5 270)
			(size 0.5 0.5)
			(layers "F.Cu" "F.Mask" "F.Paste")
			(net 1 "GND")
			(pinfunction "GND")
			(pintype "passive")
			(solder_mask_margin 0.05)
			(teardrops
				(best_length_ratio 0.4)
				(max_length 1)
				(best_width_ratio 0.9)
				(max_width 2)
				(curved_edges yes)
				(filter_ratio 0.9)
				(enabled yes)
				(allow_two_segments yes)
				(prefer_zone_connections yes)
			)
		)
		(pad "E5" smd circle
			(at -1.5 -1.5 270)
			(size 0.5 0.5)
			(layers "F.Cu" "F.Mask" "F.Paste")
			(net 746 "/2xSFP+/KR to SFI #2/~{TRST}")
			(pinfunction "~{TRST}")
			(pintype "input")
			(solder_mask_margin 0.05)
			(teardrops
				(best_length_ratio 0.4)
				(max_length 1)
				(best_width_ratio 0.9)
				(max_width 2)
				(curved_edges yes)
				(filter_ratio 0.9)
				(enabled yes)
				(allow_two_segments yes)
				(prefer_zone_connections yes)
			)
		)
		(pad "E6" smd circle
			(at -0.5 -1.5 270)
			(size 0.5 0.5)
			(layers "F.Cu" "F.Mask" "F.Paste")
			(net 74 "+1V0")
			(pinfunction "VDDD")
			(pintype "power_in")
			(solder_mask_margin 0.05)
			(teardrops
				(best_length_ratio 0.4)
				(max_length 1)
				(best_width_ratio 0.9)
				(max_width 2)
				(curved_edges yes)
				(filter_ratio 0.9)
				(enabled yes)
				(allow_two_segments yes)
				(prefer_zone_connections yes)
			)
		)
		(pad "E7" smd circle
			(at 0.5 -1.5 270)
			(size 0.5 0.5)
			(layers "F.Cu" "F.Mask" "F.Paste")
			(net 74 "+1V0")
			(pinfunction "DVDD")
			(pintype "power_in")
			(solder_mask_margin 0.05)
			(teardrops
				(best_length_ratio 0.4)
				(max_length 1)
				(best_width_ratio 0.9)
				(max_width 2)
				(curved_edges yes)
				(filter_ratio 0.9)
				(enabled yes)
				(allow_two_segments yes)
				(prefer_zone_connections yes)
			)
		)
		(pad "E8" smd circle
			(at 1.5 -1.5 270)
			(size 0.5 0.5)
			(layers "F.Cu" "F.Mask" "F.Paste")
			(net 74 "+1V0")
			(pinfunction "VDDD")
			(pintype "passive")
			(solder_mask_margin 0.05)
			(teardrops
				(best_length_ratio 0.4)
				(max_length 1)
				(best_width_ratio 0.9)
				(max_width 2)
				(curved_edges yes)
				(filter_ratio 0.9)
				(enabled yes)
				(allow_two_segments yes)
				(prefer_zone_connections yes)
			)
		)
		(pad "E9" smd circle
			(at 2.5 -1.5 270)
			(size 0.5 0.5)
			(layers "F.Cu" "F.Mask" "F.Paste")
			(net 754 "Net-(U45A-LOSA)")
			(pinfunction "LOSA")
			(pintype "output")
			(solder_mask_margin 0.05)
			(teardrops
				(best_length_ratio 0.4)
				(max_length 1)
				(best_width_ratio 0.9)
				(max_width 2)
				(curved_edges yes)
				(filter_ratio 0.9)
				(enabled yes)
				(allow_two_segments yes)
				(prefer_zone_connections yes)
			)
		)
		(pad "E10" smd circle
			(at 3.5 -1.5 270)
			(size 0.5 0.5)
			(layers "F.Cu" "F.Mask" "F.Paste")
			(net 676 "Net-(U45C-PRTAD0)")
			(pinfunction "PRTAD0")
			(pintype "input")
			(solder_mask_margin 0.05)
			(teardrops
				(best_length_ratio 0.4)
				(max_length 1)
				(best_width_ratio 0.9)
				(max_width 2)
				(curved_edges yes)
				(filter_ratio 0.9)
				(enabled yes)
				(allow_two_segments yes)
				(prefer_zone_connections yes)
			)
		)
		(pad "E11" smd circle
			(at 4.5 -1.5 270)
			(size 0.5 0.5)
			(layers "F.Cu" "F.Mask" "F.Paste")
			(net 78 "+1V8")
			(pinfunction "VDDRA_{LS/HS}")
			(pintype "passive")
			(solder_mask_margin 0.05)
			(teardrops
				(best_length_ratio 0.4)
				(max_length 1)
				(best_width_ratio 0.9)
				(max_width 2)
				(curved_edges yes)
				(filter_ratio 0.9)
				(enabled yes)
				(allow_two_segments yes)
				(prefer_zone_connections yes)
			)
		)
		(pad "E12" smd circle
			(at 5.5 -1.5 270)
			(size 0.5 0.5)
			(layers "F.Cu" "F.Mask" "F.Paste")
			(net 688 "/2xSFP+/KR to SFI #2/KR_R.RX-")
			(pinfunction "HSTXA-")
			(pintype "output")
			(solder_mask_margin 0.05)
			(teardrops
				(best_length_ratio 0.4)
				(max_length 1)
				(best_width_ratio 0.9)
				(max_width 2)
				(curved_edges yes)
				(filter_ratio 0.9)
				(enabled yes)
				(allow_two_segments yes)
				(prefer_zone_connections yes)
			)
		)
		(pad "F1" smd circle
			(at -5.5 -0.5 270)
			(size 0.5 0.5)
			(layers "F.Cu" "F.Mask" "F.Paste")
			(net 1 "GND")
			(pinfunction "GND")
			(pintype "passive")
			(solder_mask_margin 0.05)
			(teardrops
				(best_length_ratio 0.4)
				(max_length 1)
				(best_width_ratio 0.9)
				(max_width 2)
				(curved_edges yes)
				(filter_ratio 0.9)
				(enabled yes)
				(allow_two_segments yes)
				(prefer_zone_connections yes)
			)
		)
		(pad "F2" smd circle
			(at -4.5 -0.5 270)
			(size 0.5 0.5)
			(layers "F.Cu" "F.Mask" "F.Paste")
			(net 74 "+1V0")
			(pinfunction "VDDA_{LS/HS}")
			(pintype "passive")
			(solder_mask_margin 0.05)
			(teardrops
				(best_length_ratio 0.4)
				(max_length 1)
				(best_width_ratio 0.9)
				(max_width 2)
				(curved_edges yes)
				(filter_ratio 0.9)
				(enabled yes)
				(allow_two_segments yes)
				(prefer_zone_connections yes)
			)
		)
		(pad "F3" smd circle
			(at -3.5 -0.5 270)
			(size 0.5 0.5)
			(layers "F.Cu" "F.Mask" "F.Paste")
			(net 847 "unconnected-(U45A-OUTA3+-PadF3)")
			(pinfunction "OUTA3+")
			(pintype "output+no_connect")
			(solder_mask_margin 0.05)
			(teardrops
				(best_length_ratio 0.4)
				(max_length 1)
				(best_width_ratio 0.9)
				(max_width 2)
				(curved_edges yes)
				(filter_ratio 0.9)
				(enabled yes)
				(allow_two_segments yes)
				(prefer_zone_connections yes)
			)
		)
		(pad "F4" smd circle
			(at -2.5 -0.5 270)
			(size 0.5 0.5)
			(layers "F.Cu" "F.Mask" "F.Paste")
			(net 74 "+1V0")
			(pinfunction "VDDT_{LS/HS}")
			(pintype "power_in")
			(solder_mask_margin 0.05)
			(teardrops
				(best_length_ratio 0.4)
				(max_length 1)
				(best_width_ratio 0.9)
				(max_width 2)
				(curved_edges yes)
				(filter_ratio 0.9)
				(enabled yes)
				(allow_two_segments yes)
				(prefer_zone_connections yes)
			)
		)
		(pad "F5" smd circle
			(at -1.5 -0.5 270)
			(size 0.5 0.5)
			(layers "F.Cu" "F.Mask" "F.Paste")
			(net 1 "GND")
			(pinfunction "GND")
			(pintype "passive")
			(solder_mask_margin 0.05)
			(teardrops
				(best_length_ratio 0.4)
				(max_length 1)
				(best_width_ratio 0.9)
				(max_width 2)
				(curved_edges yes)
				(filter_ratio 0.9)
				(enabled yes)
				(allow_two_segments yes)
				(prefer_zone_connections yes)
			)
		)
		(pad "F6" smd circle
			(at -0.5 -0.5 270)
			(size 0.5 0.5)
			(layers "F.Cu" "F.Mask" "F.Paste")
			(net 74 "+1V0")
			(pinfunction "VDDD")
			(pintype "passive")
			(solder_mask_margin 0.05)
			(teardrops
				(best_length_ratio 0.4)
				(max_length 1)
				(best_width_ratio 0.9)
				(max_width 2)
				(curved_edges yes)
				(filter_ratio 0.9)
				(enabled yes)
				(allow_two_segments yes)
				(prefer_zone_connections yes)
			)
		)
		(pad "F7" smd circle
			(at 0.5 -0.5 270)
			(size 0.5 0.5)
			(layers "F.Cu" "F.Mask" "F.Paste")
			(net 74 "+1V0")
			(pinfunction "DVDD")
			(pintype "passive")
			(solder_mask_margin 0.05)
			(teardrops
				(best_length_ratio 0.4)
				(max_length 1)
				(best_width_ratio 0.9)
				(max_width 2)
				(curved_edges yes)
				(filter_ratio 0.9)
				(enabled yes)
				(allow_two_segments yes)
				(prefer_zone_connections yes)
			)
		)
		(pad "F8" smd circle
			(at 1.5 -0.5 270)
			(size 0.5 0.5)
			(layers "F.Cu" "F.Mask" "F.Paste")
			(net 1 "GND")
			(pinfunction "GND")
			(pintype "passive")
			(solder_mask_margin 0.05)
			(teardrops
				(best_length_ratio 0.4)
				(max_length 1)
				(best_width_ratio 0.9)
				(max_width 2)
				(curved_edges yes)
				(filter_ratio 0.9)
				(enabled yes)
				(allow_two_segments yes)
				(prefer_zone_connections yes)
			)
		)
		(pad "F9" smd circle
			(at 2.5 -0.5 270)
			(size 0.5 0.5)
			(layers "F.Cu" "F.Mask" "F.Paste")
			(net 74 "+1V0")
			(pinfunction "VDDT_{LS/HS}")
			(pintype "passive")
			(solder_mask_margin 0.05)
			(teardrops
				(best_length_ratio 0.4)
				(max_length 1)
				(best_width_ratio 0.9)
				(max_width 2)
				(curved_edges yes)
				(filter_ratio 0.9)
				(enabled yes)
				(allow_two_segments yes)
				(prefer_zone_connections yes)
			)
		)
		(pad "F10" smd circle
			(at 3.5 -0.5 270)
			(size 0.5 0.5)
			(layers "F.Cu" "F.Mask" "F.Paste")
			(net 1 "GND")
			(pinfunction "GND")
			(pintype "passive")
			(solder_mask_margin 0.05)
			(teardrops
				(best_length_ratio 0.4)
				(max_length 1)
				(best_width_ratio 0.9)
				(max_width 2)
				(curved_edges yes)
				(filter_ratio 0.9)
				(enabled yes)
				(allow_two_segments yes)
				(prefer_zone_connections yes)
			)
		)
		(pad "F11" smd circle
			(at 4.5 -0.5 270)
			(size 0.5 0.5)
			(layers "F.Cu" "F.Mask" "F.Paste")
			(net 74 "+1V0")
			(pinfunction "VDDA_{LS/HS}")
			(pintype "passive")
			(solder_mask_margin 0.05)
			(teardrops
				(best_length_ratio 0.4)
				(max_length 1)
				(best_width_ratio 0.9)
				(max_width 2)
				(curved_edges yes)
				(filter_ratio 0.9)
				(enabled yes)
				(allow_two_segments yes)
				(prefer_zone_connections yes)
			)
		)
		(pad "F12" smd circle
			(at 5.5 -0.5 270)
			(size 0.5 0.5)
			(layers "F.Cu" "F.Mask" "F.Paste")
			(net 1 "GND")
			(pinfunction "GND")
			(pintype "passive")
			(solder_mask_margin 0.05)
			(teardrops
				(best_length_ratio 0.4)
				(max_length 1)
				(best_width_ratio 0.9)
				(max_width 2)
				(curved_edges yes)
				(filter_ratio 0.9)
				(enabled yes)
				(allow_two_segments yes)
				(prefer_zone_connections yes)
			)
		)
		(pad "G1" smd circle
			(at -5.5 0.5 270)
			(size 0.5 0.5)
			(layers "F.Cu" "F.Mask" "F.Paste")
			(net 1 "GND")
			(pinfunction "GND")
			(pintype "passive")
			(solder_mask_margin 0.05)
			(teardrops
				(best_length_ratio 0.4)
				(max_length 1)
				(best_width_ratio 0.9)
				(max_width 2)
				(curved_edges yes)
				(filter_ratio 0.9)
				(enabled yes)
				(allow_two_segments yes)
				(prefer_zone_connections yes)
			)
		)
		(pad "G2" smd circle
			(at -4.5 0.5 270)
			(size 0.5 0.5)
			(layers "F.Cu" "F.Mask" "F.Paste")
			(net 74 "+1V0")
			(pinfunction "VDDA_{LS/HS}")
			(pintype "passive")
			(solder_mask_margin 0.05)
			(teardrops
				(best_length_ratio 0.4)
				(max_length 1)
				(best_width_ratio 0.9)
				(max_width 2)
				(curved_edges yes)
				(filter_ratio 0.9)
				(enabled yes)
				(allow_two_segments yes)
				(prefer_zone_connections yes)
			)
		)
		(pad "G3" smd circle
			(at -3.5 0.5 270)
			(size 0.5 0.5)
			(layers "F.Cu" "F.Mask" "F.Paste")
			(net 1 "GND")
			(pinfunction "GND")
			(pintype "passive")
			(solder_mask_margin 0.05)
			(teardrops
				(best_length_ratio 0.4)
				(max_length 1)
				(best_width_ratio 0.9)
				(max_width 2)
				(curved_edges yes)
				(filter_ratio 0.9)
				(enabled yes)
				(allow_two_segments yes)
				(prefer_zone_connections yes)
			)
		)
		(pad "G4" smd circle
			(at -2.5 0.5 270)
			(size 0.5 0.5)
			(layers "F.Cu" "F.Mask" "F.Paste")
			(net 74 "+1V0")
			(pinfunction "VDDT_{LS/HS}")
			(pintype "passive")
			(solder_mask_margin 0.05)
			(teardrops
				(best_length_ratio 0.4)
				(max_length 1)
				(best_width_ratio 0.9)
				(max_width 2)
				(curved_edges yes)
				(filter_ratio 0.9)
				(enabled yes)
				(allow_two_segments yes)
				(prefer_zone_connections yes)
			)
		)
		(pad "G5" smd circle
			(at -1.5 0.5 270)
			(size 0.5 0.5)
			(layers "F.Cu" "F.Mask" "F.Paste")
			(net 1 "GND")
			(pinfunction "GND")
			(pintype "passive")
			(solder_mask_margin 0.05)
			(teardrops
				(best_length_ratio 0.4)
				(max_length 1)
				(best_width_ratio 0.9)
				(max_width 2)
				(curved_edges yes)
				(filter_ratio 0.9)
				(enabled yes)
				(allow_two_segments yes)
				(prefer_zone_connections yes)
			)
		)
		(pad "G6" smd circle
			(at -0.5 0.5 270)
			(size 0.5 0.5)
			(layers "F.Cu" "F.Mask" "F.Paste")
			(net 74 "+1V0")
			(pinfunction "DVDD")
			(pintype "passive")
			(solder_mask_margin 0.05)
			(teardrops
				(best_length_ratio 0.4)
				(max_length 1)
				(best_width_ratio 0.9)
				(max_width 2)
				(curved_edges yes)
				(filter_ratio 0.9)
				(enabled yes)
				(allow_two_segments yes)
				(prefer_zone_connections yes)
			)
		)
		(pad "G7" smd circle
			(at 0.5 0.5 270)
			(size 0.5 0.5)
			(layers "F.Cu" "F.Mask" "F.Paste")
			(net 1 "GND")
			(pinfunction "GND")
			(pintype "passive")
			(solder_mask_margin 0.05)
			(teardrops
				(best_length_ratio 0.4)
				(max_length 1)
				(best_width_ratio 0.9)
				(max_width 2)
				(curved_edges yes)
				(filter_ratio 0.9)
				(enabled yes)
				(allow_two_segments yes)
				(prefer_zone_connections yes)
			)
		)
	)
)
